(kicad_pcb
	(version 20241229)
	(generator "pcbnew")
	(generator_version "9.0")
	(general
		(thickness 1.599998)
		(legacy_teardrops no)
	)
	(paper "A4")
	(title_block
		(title "Artix - Datacenter Secure Control Module (DC-SCM)")
		(date "2024-11-06")
		(rev "1.1.3")
		(comment 9 "footprints 31-35 of 544")
	)
	(layers
		(0 "F.Cu" signal)
		(4 "In1.Cu" signal)
		(6 "In2.Cu" signal)
		(8 "In3.Cu" signal)
		(10 "In4.Cu" signal)
		(12 "In5.Cu" signal)
		(14 "In6.Cu" signal)
		(2 "B.Cu" signal)
		(9 "F.Adhes" user "F.Adhesive")
		(11 "B.Adhes" user "B.Adhesive")
		(13 "F.Paste" user)
		(15 "B.Paste" user)
		(5 "F.SilkS" user "F.Silkscreen")
		(7 "B.SilkS" user "B.Silkscreen")
		(1 "F.Mask" user)
		(3 "B.Mask" user)
		(17 "Dwgs.User" user "User.Drawings")
		(19 "Cmts.User" user "User.Comments")
		(21 "Eco1.User" user "User.Eco1")
		(23 "Eco2.User" user "User.Eco2")
		(25 "Edge.Cuts" user)
		(27 "Margin" user)
		(31 "F.CrtYd" user "F.Courtyard")
		(29 "B.CrtYd" user "B.Courtyard")
		(35 "F.Fab" user)
		(33 "B.Fab" user)
	)
	(footprint "antmicro-footprints:C_0402_1005Metric"
		(layer "F.Cu")
		(at 85.895 92.775 180)
		(descr "Capacitor SMD 0402")
		(tags "capacitor SMD 0402")
		(property "Reference" "C88"
			(at -3.005 -0.325 0)
			(layer "F.SilkS")
			(effects
				(font
					(size 0.7 0.7)
					(thickness 0.15)
				)
				(justify right bottom)
			)
		)
		(property "Value" "C_10u_0402"
			(at 0 1.4 0)
			(layer "F.Fab")
			(effects
				(font
					(size 0.7 0.7)
					(thickness 0.15)
				)
				(justify right bottom)
			)
		)
		(property "Datasheet" "https://www.yageo.com/en/Chart/Download/pdf/CC0402MRX5R5BB106"
			(at 0 0 180)
			(layer "F.Fab")
			(hide yes)
			(effects
				(font
					(size 1.27 1.27)
					(thickness 0.15)
				)
			)
		)
		(property "Description" "SMD Multilayer Ceramic Capacitor, 10 µF, 6.3 V, 0402 [1005 Metric], ± 20%, X5R, CC Series"
			(at 0 0 180)
			(layer "F.Fab")
			(hide yes)
			(effects
				(font
					(size 1.27 1.27)
					(thickness 0.15)
				)
			)
		)
		(property "Author" "Antmicro"
			(at 171.79 185.55 0)
			(layer "F.Fab")
			(hide yes)
			(effects
				(font
					(size 1 1)
					(thickness 0.15)
				)
			)
		)
		(property "Dielectric" ""
			(at 171.79 185.55 0)
			(layer "F.Fab")
			(hide yes)
			(effects
				(font
					(size 1 1)
					(thickness 0.15)
				)
			)
		)
		(property "License" "Apache-2.0"
			(at 171.79 185.55 0)
			(layer "F.Fab")
			(hide yes)
			(effects
				(font
					(size 1 1)
					(thickness 0.15)
				)
			)
		)
		(property "MPN" "CC0402MRX5R5BB106"
			(at 171.79 185.55 0)
			(layer "F.Fab")
			(hide yes)
			(effects
				(font
					(size 1 1)
					(thickness 0.15)
				)
			)
		)
		(property "Manufacturer" "YAGEO"
			(at 171.79 185.55 0)
			(layer "F.Fab")
			(hide yes)
			(effects
				(font
					(size 1 1)
					(thickness 0.15)
				)
			)
		)
		(property "Val" "10u"
			(at 171.79 185.55 0)
			(layer "F.Fab")
			(hide yes)
			(effects
				(font
					(size 1 1)
					(thickness 0.15)
				)
			)
		)
		(property "Voltage" ""
			(at 171.79 185.55 0)
			(layer "F.Fab")
			(hide yes)
			(effects
				(font
					(size 1 1)
					(thickness 0.15)
				)
			)
		)
		(sheetname "/Power supply/")
		(sheetfile "power-supply.kicad_sch")
		(attr smd)
		(fp_rect
			(start -0.925 -0.47)
			(end 0.925 0.47)
			(stroke
				(width 0.05)
				(type default)
			)
			(fill no)
			(layer "F.CrtYd")
		)
		(fp_line
			(start 0.504 0.248)
			(end -0.494 0.248)
			(stroke
				(width 0.15)
				(type solid)
			)
			(layer "F.Fab")
		)
		(fp_line
			(start 0.504 -0.25)
			(end 0.504 0.248)
			(stroke
				(width 0.15)
				(type solid)
			)
			(layer "F.Fab")
		)
		(fp_line
			(start -0.494 0.248)
			(end -0.494 -0.25)
			(stroke
				(width 0.15)
				(type solid)
			)
			(layer "F.Fab")
		)
		(fp_line
			(start -0.494 -0.25)
			(end 0.504 -0.25)
			(stroke
				(width 0.15)
				(type solid)
			)
			(layer "F.Fab")
		)
		(pad "1" smd roundrect
			(at -0.48 0 180)
			(size 0.59 0.64)
			(layers "F.Cu" "F.Mask" "F.Paste")
			(roundrect_rratio 0.25)
			(net 1 "GND")
			(pintype "passive")
		)
		(pad "2" smd roundrect
			(at 0.48 0 180)
			(size 0.59 0.64)
			(layers "F.Cu" "F.Mask" "F.Paste")
			(roundrect_rratio 0.25)
			(net 275 "Net-(C80-Pad2)")
			(pintype "passive")
		)
	)
	(footprint "antmicro-footprints:R_0402_1005Metric"
		(layer "F.Cu")
		(at 90.545 103.925 -90)
		(descr "Resistor SMD 0402")
		(tags "resistor SMD 0402")
		(property "Reference" "R73"
			(at -1.225 -3.355 90)
			(layer "F.SilkS")
			(effects
				(font
					(size 0.7 0.7)
					(thickness 0.15)
				)
				(justify right bottom)
			)
		)
		(property "Value" "R_453k_0402"
			(at 0 1.4 90)
			(layer "F.Fab")
			(effects
				(font
					(size 0.7 0.7)
					(thickness 0.15)
				)
				(justify right bottom)
			)
		)
		(property "Datasheet" "https://www.bourns.com/docs/product-datasheets/cr.pdf"
			(at 0 0 270)
			(layer "F.Fab")
			(hide yes)
			(effects
				(font
					(size 1.27 1.27)
					(thickness 0.15)
				)
			)
		)
		(property "Description" "SMD Chip Resistor"
			(at 0 0 270)
			(layer "F.Fab")
			(hide yes)
			(effects
				(font
					(size 1.27 1.27)
					(thickness 0.15)
				)
			)
		)
		(property "Author" "Antmicro"
			(at -13.38 194.47 0)
			(layer "F.Fab")
			(hide yes)
			(effects
				(font
					(size 1 1)
					(thickness 0.15)
				)
			)
		)
		(property "License" "Apache-2.0"
			(at -13.38 194.47 0)
			(layer "F.Fab")
			(hide yes)
			(effects
				(font
					(size 1 1)
					(thickness 0.15)
				)
			)
		)
		(property "MPN" "CR0402-FX-4533GLF"
			(at -13.38 194.47 0)
			(layer "F.Fab")
			(hide yes)
			(effects
				(font
					(size 1 1)
					(thickness 0.15)
				)
			)
		)
		(property "Manufacturer" "Bourns"
			(at -13.38 194.47 0)
			(layer "F.Fab")
			(hide yes)
			(effects
				(font
					(size 1 1)
					(thickness 0.15)
				)
			)
		)
		(property "Tolerance" "1%"
			(at -13.38 194.47 0)
			(layer "F.Fab")
			(hide yes)
			(effects
				(font
					(size 1 1)
					(thickness 0.15)
				)
			)
		)
		(property "Val" "453k"
			(at -13.38 194.47 0)
			(layer "F.Fab")
			(hide yes)
			(effects
				(font
					(size 1 1)
					(thickness 0.15)
				)
			)
		)
		(sheetname "/Power supply/")
		(sheetfile "power-supply.kicad_sch")
		(attr smd)
		(fp_rect
			(start -0.925 -0.47)
			(end 0.925 0.47)
			(stroke
				(width 0.05)
				(type default)
			)
			(fill no)
			(layer "F.CrtYd")
		)
		(fp_rect
			(start -0.5 -0.25)
			(end 0.5 0.25)
			(stroke
				(width 0.15)
				(type solid)
			)
			(fill no)
			(layer "F.Fab")
		)
		(pad "1" smd roundrect
			(at -0.48 0 270)
			(size 0.59 0.64)
			(layers "F.Cu" "F.Mask" "F.Paste")
			(roundrect_rratio 0.25)
			(net 274 "Net-(C79-Pad2)")
			(pintype "passive")
		)
		(pad "2" smd roundrect
			(at 0.48 0 270)
			(size 0.59 0.64)
			(layers "F.Cu" "F.Mask" "F.Paste")
			(roundrect_rratio 0.25)
			(net 113 "Net-(U10-FB)")
			(pintype "passive")
		)
	)
	(footprint "antmicro-footprints:R_0402_1005Metric"
		(layer "F.Cu")
		(at 89.545 96.575 90)
		(descr "Resistor SMD 0402")
		(tags "resistor SMD 0402")
		(property "Reference" "R76"
			(at 0.775 0.355 90)
			(layer "F.SilkS")
			(effects
				(font
					(size 0.7 0.7)
					(thickness 0.15)
				)
				(justify left bottom)
			)
		)
		(property "Value" "R_100k_0402"
			(at 0 1.4 90)
			(layer "F.Fab")
			(effects
				(font
					(size 0.7 0.7)
					(thickness 0.15)
				)
				(justify left bottom)
			)
		)
		(property "Datasheet" "https://www.bourns.com/docs/product-datasheets/cr.pdf"
			(at 0 0 90)
			(layer "F.Fab")
			(hide yes)
			(effects
				(font
					(size 1.27 1.27)
					(thickness 0.15)
				)
			)
		)
		(property "Description" "SMD Chip Resistor, 100 kohm, ± 1%, 62.5 mW, 0402 [1005 Metric], Thick Film, General Purpose"
			(at 0 0 90)
			(layer "F.Fab")
			(hide yes)
			(effects
				(font
					(size 1.27 1.27)
					(thickness 0.15)
				)
			)
		)
		(property "Author" "Antmicro"
			(at 186.12 7.03 0)
			(layer "F.Fab")
			(hide yes)
			(effects
				(font
					(size 1 1)
					(thickness 0.15)
				)
			)
		)
		(property "License" "Apache-2.0"
			(at 186.12 7.03 0)
			(layer "F.Fab")
			(hide yes)
			(effects
				(font
					(size 1 1)
					(thickness 0.15)
				)
			)
		)
		(property "MPN" "CR0402-FX-1003GLF"
			(at 186.12 7.03 0)
			(layer "F.Fab")
			(hide yes)
			(effects
				(font
					(size 1 1)
					(thickness 0.15)
				)
			)
		)
		(property "Manufacturer" "Bourns"
			(at 186.12 7.03 0)
			(layer "F.Fab")
			(hide yes)
			(effects
				(font
					(size 1 1)
					(thickness 0.15)
				)
			)
		)
		(property "Tolerance" "1%"
			(at 186.12 7.03 0)
			(layer "F.Fab")
			(hide yes)
			(effects
				(font
					(size 1 1)
					(thickness 0.15)
				)
			)
		)
		(property "Val" "100k"
			(at 186.12 7.03 0)
			(layer "F.Fab")
			(hide yes)
			(effects
				(font
					(size 1 1)
					(thickness 0.15)
				)
			)
		)
		(sheetname "/Power supply/")
		(sheetfile "power-supply.kicad_sch")
		(attr smd)
		(fp_rect
			(start -0.925 -0.47)
			(end 0.925 0.47)
			(stroke
				(width 0.05)
				(type default)
			)
			(fill no)
			(layer "F.CrtYd")
		)
		(fp_rect
			(start -0.5 -0.25)
			(end 0.5 0.25)
			(stroke
				(width 0.15)
				(type solid)
			)
			(fill no)
			(layer "F.Fab")
		)
		(pad "1" smd roundrect
			(at -0.48 0 90)
			(size 0.59 0.64)
			(layers "F.Cu" "F.Mask" "F.Paste")
			(roundrect_rratio 0.25)
			(net 117 "Net-(U11-FB)")
			(pintype "passive")
		)
		(pad "2" smd roundrect
			(at 0.48 0 90)
			(size 0.59 0.64)
			(layers "F.Cu" "F.Mask" "F.Paste")
			(roundrect_rratio 0.25)
			(net 1 "GND")
			(pintype "passive")
		)
	)
	(footprint "antmicro-footprints:QFN-8_2x1.5mm"
		(layer "F.Cu")
		(at 86.995 96.775 180)
		(property "Reference" "U11"
			(at 0.305 -2.205 180)
			(layer "F.SilkS")
			(effects
				(font
					(size 0.7 0.7)
					(thickness 0.15)
				)
				(justify left bottom)
			)
		)
		(property "Value" "TPS62823DLCT"
			(at 0 2.2 180)
			(layer "F.Fab")
			(effects
				(font
					(size 0.7 0.7)
					(thickness 0.15)
				)
				(justify left bottom)
			)
		)
		(property "Datasheet" "https://www.ti.com/lit/ds/symlink/tps62823.pdf?ts=1685970309606&ref_url=https%253A%252F%252Fwww.ti.com%252Fproduct%252FTPS62823%252Fpart-details%252FTPS62823DLCT"
			(at 0 0 180)
			(layer "F.Fab")
			(hide yes)
			(effects
				(font
					(size 1.27 1.27)
					(thickness 0.15)
				)
			)
		)
		(property "Description" "DC/DC converter"
			(at 0 0 180)
			(layer "F.Fab")
			(hide yes)
			(effects
				(font
					(size 1.27 1.27)
					(thickness 0.15)
				)
			)
		)
		(property "Author" "Antmicro"
			(at 173.99 193.55 0)
			(layer "F.Fab")
			(hide yes)
			(effects
				(font
					(size 1 1)
					(thickness 0.15)
				)
			)
		)
		(property "License" "Apache-2.0"
			(at 173.99 193.55 0)
			(layer "F.Fab")
			(hide yes)
			(effects
				(font
					(size 1 1)
					(thickness 0.15)
				)
			)
		)
		(property "MPN" "TPS62823DLCT"
			(at 173.99 193.55 0)
			(layer "F.Fab")
			(hide yes)
			(effects
				(font
					(size 1 1)
					(thickness 0.15)
				)
			)
		)
		(property "Manufacturer" "Texas Instruments"
			(at 173.99 193.55 0)
			(layer "F.Fab")
			(hide yes)
			(effects
				(font
					(size 1 1)
					(thickness 0.15)
				)
			)
		)
		(sheetname "/Power supply/")
		(sheetfile "power-supply.kicad_sch")
		(attr smd)
		(fp_line
			(start -0.25 -1.05)
			(end 0.9 -1.05)
			(stroke
				(width 0.15)
				(type solid)
			)
			(layer "F.SilkS")
		)
		(fp_line
			(start -0.9 1.05)
			(end 0.9 1.05)
			(stroke
				(width 0.15)
				(type solid)
			)
			(layer "F.SilkS")
		)
		(fp_circle
			(center -0.9 -1.05)
			(end -0.849 -1.05)
			(stroke
				(width 0.15)
				(type solid)
			)
			(fill yes)
			(layer "F.SilkS")
		)
		(fp_rect
			(start -1.1 -1.25)
			(end 1.1 1.25)
			(stroke
				(width 0.05)
				(type solid)
			)
			(fill no)
			(layer "F.CrtYd")
		)
		(fp_line
			(start 0.998 0.998)
			(end -1 0.998)
			(stroke
				(width 0.15)
				(type solid)
			)
			(layer "F.Fab")
		)
		(fp_line
			(start 0.998 -1)
			(end 0.998 0.998)
			(stroke
				(width 0.15)
				(type solid)
			)
			(layer "F.Fab")
		)
		(fp_line
			(start -0.5 -1)
			(end 0.998 -1)
			(stroke
				(width 0.15)
				(type solid)
			)
			(layer "F.Fab")
		)
		(fp_line
			(start -1 0.998)
			(end -1 -0.5)
			(stroke
				(width 0.15)
				(type solid)
			)
			(layer "F.Fab")
		)
		(fp_line
			(start -1 -0.5)
			(end -0.5 -1)
			(stroke
				(width 0.15)
				(type solid)
			)
			(layer "F.Fab")
		)
		(pad "1" smd rect
			(at -0.677 -0.75 180)
			(size 0.55 0.25)
			(layers "F.Cu" "F.Mask" "F.Paste")
			(net 315 "Net-(U11-EN)")
			(pinfunction "EN")
			(pintype "input")
		)
		(pad "2" smd rect
			(at -0.677 -0.25 180)
			(size 0.55 0.25)
			(layers "F.Cu" "F.Mask" "F.Paste")
			(net 117 "Net-(U11-FB)")
			(pinfunction "FB")
			(pintype "bidirectional")
		)
		(pad "3" smd rect
			(at -0.677 0.248 180)
			(size 0.55 0.25)
			(layers "F.Cu" "F.Mask" "F.Paste")
			(net 1 "GND")
			(pinfunction "AGND")
			(pintype "power_in")
		)
		(pad "4" smd rect
			(at -0.677 0.748 180)
			(size 0.55 0.25)
			(layers "F.Cu" "F.Mask" "F.Paste")
			(net 530 "unconnected-(U11-NC-Pad4)")
			(pinfunction "NC")
			(pintype "no_connect")
		)
		(pad "5" smd rect
			(at 0.675 0.748 180)
			(size 0.55 0.25)
			(layers "F.Cu" "F.Mask" "F.Paste")
			(net 1 "GND")
			(pinfunction "PGND")
			(pintype "power_in")
		)
		(pad "6" smd rect
			(at 0.675 0.248 180)
			(size 0.55 0.25)
			(layers "F.Cu" "F.Mask" "F.Paste")
			(net 288 "Net-(U11-SW)")
			(pinfunction "SW")
			(pintype "bidirectional")
		)
		(pad "7" smd rect
			(at 0.675 -0.25 180)
			(size 0.55 0.25)
			(layers "F.Cu" "F.Mask" "F.Paste")
			(net 4 "VCC5V0")
			(pinfunction "VIN")
			(pintype "power_in")
		)
		(pad "8" smd rect
			(at 0.675 -0.75 180)
			(size 0.55 0.25)
			(layers "F.Cu" "F.Mask" "F.Paste")
			(net 292 "/Power supply/1V8_PG")
			(pinfunction "PG")
			(pintype "output")
		)
	)
	(footprint "antmicro-footprints:C_0402_1005Metric"
		(layer "F.Cu")
		(at 128.996 168.181 -90)
		(descr "Capacitor SMD 0402")
		(tags "capacitor SMD 0402")
		(property "Reference" "C179"
			(at 0.819 -0.404 90)
			(layer "F.SilkS")
			(effects
				(font
					(size 0.7 0.7)
					(thickness 0.15)
				)
				(justify right bottom)
			)
		)
		(property "Value" "C_100n_6V3_0402"
			(at 0 1.4 90)
			(layer "F.Fab")
			(effects
				(font
					(size 0.7 0.7)
					(thickness 0.15)
				)
				(justify right bottom)
			)
		)
		(property "Datasheet" "https://www.passivecomponent.com/wp-content/uploads/datasheet/WTC_MLCC_General_Purpose.pdf"
			(at 0 0 270)
			(layer "F.Fab")
			(hide yes)
			(effects
				(font
					(size 1.27 1.27)
					(thickness 0.15)
				)
			)
		)
		(property "Description" "SMT Multilayer Ceramic Capacitor, 0.1 µF, 6.3 V, 0402 [1005 Metric], ± 10%, X5R, Walsin MLCC"
			(at 0 0 270)
			(layer "F.Fab")
			(hide yes)
			(effects
				(font
					(size 1.27 1.27)
					(thickness 0.15)
				)
			)
		)
		(property "Author" "Antmicro"
			(at -39.185 297.177 0)
			(layer "F.Fab")
			(hide yes)
			(effects
				(font
					(size 1 1)
					(thickness 0.15)
				)
			)
		)
		(property "Dielectric" ""
			(at -39.185 297.177 0)
			(layer "F.Fab")
			(hide yes)
			(effects
				(font
					(size 1 1)
					(thickness 0.15)
				)
			)
		)
		(property "License" "Apache-2.0"
			(at -39.185 297.177 0)
			(layer "F.Fab")
			(hide yes)
			(effects
				(font
					(size 1 1)
					(thickness 0.15)
				)
			)
		)
		(property "MPN" "0402X104K6R3CT"
			(at -39.185 297.177 0)
			(layer "F.Fab")
			(hide yes)
			(effects
				(font
					(size 1 1)
					(thickness 0.15)
				)
			)
		)
		(property "Manufacturer" "Walsin"
			(at -39.185 297.177 0)
			(layer "F.Fab")
			(hide yes)
			(effects
				(font
					(size 1 1)
					(thickness 0.15)
				)
			)
		)
		(property "Public" "False"
			(at -39.185 297.177 0)
			(layer "F.Fab")
			(hide yes)
			(effects
				(font
					(size 1 1)
					(thickness 0.15)
				)
			)
		)
		(property "Val" "100n"
			(at -39.185 297.177 0)
			(layer "F.Fab")
			(hide yes)
			(effects
				(font
					(size 1 1)
					(thickness 0.15)
				)
			)
		)
		(property "Voltage" ""
			(at -39.185 297.177 0)
			(layer "F.Fab")
			(hide yes)
			(effects
				(font
					(size 1 1)
					(thickness 0.15)
				)
			)
		)
		(sheetname "/PCIe-connector/")
		(sheetfile "pcie-conn.kicad_sch")
		(attr smd)
		(fp_rect
			(start -0.925 -0.47)
			(end 0.925 0.47)
			(stroke
				(width 0.05)
				(type default)
			)
			(fill no)
			(layer "F.CrtYd")
		)
		(fp_line
			(start -0.494 0.248)
			(end -0.494 -0.25)
			(stroke
				(width 0.15)
				(type solid)
			)
			(layer "F.Fab")
		)
		(fp_line
			(start 0.504 0.248)
			(end -0.494 0.248)
			(stroke
				(width 0.15)
				(type solid)
			)
			(layer "F.Fab")
		)
		(fp_line
			(start -0.494 -0.25)
			(end 0.504 -0.25)
			(stroke
				(width 0.15)
				(type solid)
			)
			(layer "F.Fab")
		)
		(fp_line
			(start 0.504 -0.25)
			(end 0.504 0.248)
			(stroke
				(width 0.15)
				(type solid)
			)
			(layer "F.Fab")
		)
		(pad "1" smd roundrect
			(at -0.48 0 270)
			(size 0.59 0.64)
			(layers "F.Cu" "F.Mask" "F.Paste")
			(roundrect_rratio 0.25)
			(net 373 "/PCIe-connector/PCIE_HPM_TX2_C_P")
			(pintype "passive")
		)
		(pad "2" smd roundrect
			(at 0.48 0 270)
			(size 0.59 0.64)
			(layers "F.Cu" "F.Mask" "F.Paste")
			(roundrect_rratio 0.25)
			(net 355 "PCIE_HPM_TX[2]_P")
			(pintype "passive")
		)
	)
)
